(kicad_pcb
	(version 20260206)
	(generator "pcbnew")
	(generator_version "10.0")
	(general
		(thickness 1.6)
		(legacy_teardrops no)
	)
	(paper "A4")
	(title_block
		(title "Bryce Canyon_IOM_M2_16342-2_OCP.brd")
		(comment 1 "Bryce Canyon / footprints 895-902 of 1146")
	)
	(layers
		(0 "F.Cu" signal "TOP")
		(4 "In1.Cu" signal "L2GND")
		(6 "In2.Cu" signal "L3")
		(8 "In3.Cu" signal "L4VCC")
		(10 "In4.Cu" signal "L5VCC")
		(12 "In5.Cu" signal "L6")
		(14 "In6.Cu" signal "L7GND")
		(2 "B.Cu" signal "BOTTOM")
		(9 "F.Adhes" user "F.Adhesive")
		(11 "B.Adhes" user "B.Adhesive")
		(13 "F.Paste" user "Package Geometry/Pastemask Top")
		(15 "B.Paste" user "Package Geometry/Pastemask Bottom")
		(5 "F.SilkS" user "Ref Des/Silkscreen Top")
		(7 "B.SilkS" user "Ref Des/Silkscreen Bottom")
		(1 "F.Mask" user "Board Geometry/Soldermask Top")
		(3 "B.Mask" user "Board Geometry/Soldermask Bottom")
		(17 "Dwgs.User" user "User.Drawings")
		(19 "Cmts.User" user "User.Comments")
		(21 "Eco1.User" user "User.Eco1")
		(23 "Eco2.User" user "User.Eco2")
		(25 "Edge.Cuts" user "Board Geometry/Outline")
		(27 "Margin" user)
		(31 "F.CrtYd" user "Package Geometry/Place Bound Top")
		(29 "B.CrtYd" user "Package Geometry/Place Bound Bottom")
		(35 "F.Fab" user "Ref Des/Assembly Top")
		(33 "B.Fab" user "Ref Des/Assembly Bottom")
	)
	(footprint ""
		(layer "B.Cu")
		(at 45.466 -128.2192)
		(property "Reference" "R292"
			(at 0 0 0)
			(layer "B.SilkS")
			(hide yes)
			(effects
				(font
					(size 1.27 1.27)
				)
				(justify mirror)
			)
		)
		(property "Value" "0R2J-2-GP"
			(at -0.064008 -3.993896 0)
			(unlocked yes)
			(layer "B.Fab")
			(hide yes)
			(effects
				(font
					(size 1.016 1.016)
					(thickness 0.1524)
				)
				(justify mirror)
			)
		)
		(property "Device Type" "R402H16"
			(at -0.064008 -5.517896 0)
			(unlocked yes)
			(layer "B.Fab")
			(hide yes)
			(effects
				(font
					(size 1.016 1.016)
					(thickness 0.1524)
				)
				(justify mirror)
			)
		)
		(duplicate_pad_numbers_are_jumpers no)
		(fp_line
			(start -0.508 -0.9398)
			(end 0.508 -0.9398)
			(stroke
				(width 0.1524)
				(type default)
			)
			(layer "B.SilkS")
		)
		(fp_line
			(start 0.508 -0.9398)
			(end 0.508 0.9398)
			(stroke
				(width 0.1524)
				(type default)
			)
			(layer "B.SilkS")
		)
		(fp_rect
			(start 0.508 0.9398)
			(end -0.508 -0.9398)
			(stroke
				(width 0)
				(type default)
			)
			(fill no)
			(layer "B.CrtYd")
		)
		(fp_rect
			(start 0.508 0.9398)
			(end -0.508 -0.9398)
			(stroke
				(width 0)
				(type default)
			)
			(fill no)
			(layer "B.Fab")
		)
		(pad "1" smd custom
			(at 0 -0.4445 180)
			(size 0.1397 0.1397)
			(layers "B.Cu" "B.Mask" "B.Paste")
			(net "IOM_LOC_INS_N")
			(options
				(clearance outline)
				(anchor circle)
			)
			(primitives
				(gr_poly
					(pts
						(arc
							(start -0.1778 0.2794)
							(mid -0.249642 0.249642)
							(end -0.2794 0.1778)
						)
						(arc
							(start -0.2794 -0.1778)
							(mid -0.249642 -0.249642)
							(end -0.1778 -0.2794)
						)
						(arc
							(start 0.1778 -0.2794)
							(mid 0.249642 -0.249642)
							(end 0.2794 -0.1778)
						)
						(arc
							(start 0.2794 0.1778)
							(mid 0.249642 0.249642)
							(end 0.1778 0.2794)
						)
					)
					(width 0)
					(fill yes)
				)
			)
		)
		(pad "2" smd custom
			(at 0 0.4445 180)
			(size 0.1397 0.1397)
			(layers "B.Cu" "B.Mask" "B.Paste")
			(net "GND")
			(options
				(clearance outline)
				(anchor circle)
			)
			(primitives
				(gr_poly
					(pts
						(arc
							(start -0.1778 0.2794)
							(mid -0.249642 0.249642)
							(end -0.2794 0.1778)
						)
						(arc
							(start -0.2794 -0.1778)
							(mid -0.249642 -0.249642)
							(end -0.1778 -0.2794)
						)
						(arc
							(start 0.1778 -0.2794)
							(mid 0.249642 -0.249642)
							(end 0.2794 -0.1778)
						)
						(arc
							(start 0.2794 0.1778)
							(mid 0.249642 0.249642)
							(end 0.1778 0.2794)
						)
					)
					(width 0)
					(fill yes)
				)
			)
		)
	)
	(footprint ""
		(layer "B.Cu")
		(at 40.0812 -153.1366 -90)
		(property "Reference" "TP65"
			(at 0 0 90)
			(layer "B.SilkS")
			(hide yes)
			(effects
				(font
					(size 1.27 1.27)
				)
				(justify mirror)
			)
		)
		(property "Value" "TPAD28-2-GP"
			(at 0.0127 -1.6637 270)
			(unlocked yes)
			(layer "B.Fab")
			(hide yes)
			(effects
				(font
					(size 1.016 1.016)
					(thickness 0.1524)
				)
				(justify mirror)
			)
		)
		(property "Device Type" "TPAD28"
			(at 0.0127 -3.1877 270)
			(unlocked yes)
			(layer "B.Fab")
			(hide yes)
			(effects
				(font
					(size 1.016 1.016)
					(thickness 0.1524)
				)
				(justify mirror)
			)
		)
		(duplicate_pad_numbers_are_jumpers no)
		(fp_poly
			(pts
				(arc
					(start 0 -0.3556)
					(mid 0 0.3556)
					(end 0 -0.3556)
				)
			)
			(stroke
				(width 0)
				(type default)
			)
			(fill no)
			(layer "B.CrtYd")
		)
		(fp_poly
			(pts
				(arc
					(start 0 -0.6096)
					(mid 0 0.6096)
					(end 0 -0.6096)
				)
			)
			(stroke
				(width 0)
				(type default)
			)
			(fill no)
			(layer "B.Fab")
		)
		(pad "1" smd circle
			(at 0 0 90)
			(size 0.7112 0.7112)
			(layers "B.Cu" "B.Mask" "B.Paste")
			(net "TP_BMC_GPION6")
		)
	)
	(footprint ""
		(layer "B.Cu")
		(at 32.131 -155.067 90)
		(property "Reference" "R336"
			(at 0 0 90)
			(layer "B.SilkS")
			(hide yes)
			(effects
				(font
					(size 1.27 1.27)
				)
				(justify mirror)
			)
		)
		(property "Value" "4K7R2F-GP"
			(at -0.064008 -3.993896 90)
			(unlocked yes)
			(layer "B.Fab")
			(hide yes)
			(effects
				(font
					(size 1.016 1.016)
					(thickness 0.1524)
				)
				(justify mirror)
			)
		)
		(property "Device Type" "R402H16"
			(at -0.064008 -5.517896 90)
			(unlocked yes)
			(layer "B.Fab")
			(hide yes)
			(effects
				(font
					(size 1.016 1.016)
					(thickness 0.1524)
				)
				(justify mirror)
			)
		)
		(duplicate_pad_numbers_are_jumpers no)
		(fp_line
			(start 0.508 -0.9398)
			(end 0.508 0.9398)
			(stroke
				(width 0.1524)
				(type default)
			)
			(layer "B.SilkS")
		)
		(fp_line
			(start -0.508 -0.9398)
			(end 0.508 -0.9398)
			(stroke
				(width 0.1524)
				(type default)
			)
			(layer "B.SilkS")
		)
		(fp_rect
			(start 0.508 0.9398)
			(end -0.508 -0.9398)
			(stroke
				(width 0)
				(type default)
			)
			(fill no)
			(layer "B.CrtYd")
		)
		(fp_rect
			(start 0.508 0.9398)
			(end -0.508 -0.9398)
			(stroke
				(width 0)
				(type default)
			)
			(fill no)
			(layer "B.Fab")
		)
		(pad "1" smd custom
			(at 0 -0.4445 270)
			(size 0.1397 0.1397)
			(layers "B.Cu" "B.Mask" "B.Paste")
			(net "P3V3_STBY")
			(options
				(clearance outline)
				(anchor circle)
			)
			(primitives
				(gr_poly
					(pts
						(arc
							(start -0.1778 0.2794)
							(mid -0.249642 0.249642)
							(end -0.2794 0.1778)
						)
						(arc
							(start -0.2794 -0.1778)
							(mid -0.249642 -0.249642)
							(end -0.1778 -0.2794)
						)
						(arc
							(start 0.1778 -0.2794)
							(mid 0.249642 -0.249642)
							(end 0.2794 -0.1778)
						)
						(arc
							(start 0.2794 0.1778)
							(mid 0.249642 0.249642)
							(end 0.1778 0.2794)
						)
					)
					(width 0)
					(fill yes)
				)
			)
		)
		(pad "2" smd custom
			(at 0 0.4445 270)
			(size 0.1397 0.1397)
			(layers "B.Cu" "B.Mask" "B.Paste")
			(net "ENCL_FAULT_LED")
			(options
				(clearance outline)
				(anchor circle)
			)
			(primitives
				(gr_poly
					(pts
						(arc
							(start -0.1778 0.2794)
							(mid -0.249642 0.249642)
							(end -0.2794 0.1778)
						)
						(arc
							(start -0.2794 -0.1778)
							(mid -0.249642 -0.249642)
							(end -0.1778 -0.2794)
						)
						(arc
							(start 0.1778 -0.2794)
							(mid 0.249642 -0.249642)
							(end 0.2794 -0.1778)
						)
						(arc
							(start 0.2794 0.1778)
							(mid 0.249642 0.249642)
							(end 0.1778 0.2794)
						)
					)
					(width 0)
					(fill yes)
				)
			)
		)
	)
	(footprint ""
		(layer "B.Cu")
		(at 224.989644 -70.03923 90)
		(property "Reference" "C660"
			(at 0 0 90)
			(layer "B.SilkS")
			(hide yes)
			(effects
				(font
					(size 1.27 1.27)
				)
				(justify mirror)
			)
		)
		(property "Value" "SC10U6D3V5KX-4GP"
			(at 0.0762 -6.1214 90)
			(unlocked yes)
			(layer "B.Fab")
			(hide yes)
			(effects
				(font
					(size 1.016 1.016)
					(thickness 0.1524)
				)
				(justify mirror)
			)
		)
		(property "Device Type" "C805H58"
			(at 0.0762 -8.1534 90)
			(unlocked yes)
			(layer "B.Fab")
			(hide yes)
			(effects
				(font
					(size 1.016 1.016)
					(thickness 0.1524)
				)
				(justify mirror)
			)
		)
		(duplicate_pad_numbers_are_jumpers no)
		(fp_line
			(start -0.635 0)
			(end 0.635 0)
			(stroke
				(width 0.508)
				(type default)
			)
			(layer "B.SilkS")
		)
		(fp_rect
			(start 0.9652 1.778)
			(end -0.9652 -1.778)
			(stroke
				(width 0)
				(type default)
			)
			(fill no)
			(layer "B.CrtYd")
		)
		(fp_poly
			(pts
				(xy 0.9652 -1.778) (xy -0.9652 -1.778) (xy -0.9652 1.778) (xy 0.9652 1.778)
			)
			(stroke
				(width 0)
				(type default)
			)
			(fill no)
			(layer "B.Fab")
		)
		(pad "1" smd rect
			(at 0 -0.9652 270)
			(size 1.397 1.143)
			(layers "B.Cu" "B.Mask" "B.Paste")
			(net "P3V3_M2")
		)
		(pad "2" smd rect
			(at 0 0.9652 270)
			(size 1.397 1.143)
			(layers "B.Cu" "B.Mask" "B.Paste")
			(net "GND")
		)
	)
	(footprint ""
		(layer "B.Cu")
		(at 175.006 -124.614686 90)
		(property "Reference" "C621"
			(at 0 0 90)
			(layer "B.SilkS")
			(hide yes)
			(effects
				(font
					(size 1.27 1.27)
				)
				(justify mirror)
			)
		)
		(property "Value" "SC10U6D3V5KX-4GP"
			(at 0.0762 -6.1214 90)
			(unlocked yes)
			(layer "B.Fab")
			(hide yes)
			(effects
				(font
					(size 1.016 1.016)
					(thickness 0.1524)
				)
				(justify mirror)
			)
		)
		(property "Device Type" "C805H58"
			(at 0.0762 -8.1534 90)
			(unlocked yes)
			(layer "B.Fab")
			(hide yes)
			(effects
				(font
					(size 1.016 1.016)
					(thickness 0.1524)
				)
				(justify mirror)
			)
		)
		(duplicate_pad_numbers_are_jumpers no)
		(fp_line
			(start -0.635 0)
			(end 0.635 0)
			(stroke
				(width 0.508)
				(type default)
			)
			(layer "B.SilkS")
		)
		(fp_rect
			(start 0.9652 1.778)
			(end -0.9652 -1.778)
			(stroke
				(width 0)
				(type default)
			)
			(fill no)
			(layer "B.CrtYd")
		)
		(fp_poly
			(pts
				(xy 0.9652 -1.778) (xy -0.9652 -1.778) (xy -0.9652 1.778) (xy 0.9652 1.778)
			)
			(stroke
				(width 0)
				(type default)
			)
			(fill no)
			(layer "B.Fab")
		)
		(pad "1" smd rect
			(at 0 -0.9652 270)
			(size 1.397 1.143)
			(layers "B.Cu" "B.Mask" "B.Paste")
			(net "P3V3_M2")
		)
		(pad "2" smd rect
			(at 0 0.9652 270)
			(size 1.397 1.143)
			(layers "B.Cu" "B.Mask" "B.Paste")
			(net "GND")
		)
	)
	(footprint ""
		(layer "B.Cu")
		(at 38.757606 -123.896374 180)
		(property "Reference" "R350"
			(at 0 0 0)
			(layer "B.SilkS")
			(hide yes)
			(effects
				(font
					(size 1.27 1.27)
				)
				(justify mirror)
			)
		)
		(property "Value" "0R2J-2-GP"
			(at -0.064008 -3.993896 180)
			(unlocked yes)
			(layer "B.Fab")
			(hide yes)
			(effects
				(font
					(size 1.016 1.016)
					(thickness 0.1524)
				)
				(justify mirror)
			)
		)
		(property "Device Type" "R402H16"
			(at -0.064008 -5.517896 180)
			(unlocked yes)
			(layer "B.Fab")
			(hide yes)
			(effects
				(font
					(size 1.016 1.016)
					(thickness 0.1524)
				)
				(justify mirror)
			)
		)
		(duplicate_pad_numbers_are_jumpers no)
		(fp_line
			(start 0.508 -0.9398)
			(end 0.508 0.9398)
			(stroke
				(width 0.1524)
				(type default)
			)
			(layer "B.SilkS")
		)
		(fp_line
			(start -0.508 -0.9398)
			(end 0.508 -0.9398)
			(stroke
				(width 0.1524)
				(type default)
			)
			(layer "B.SilkS")
		)
		(fp_rect
			(start 0.508 0.9398)
			(end -0.508 -0.9398)
			(stroke
				(width 0)
				(type default)
			)
			(fill no)
			(layer "B.CrtYd")
		)
		(fp_rect
			(start 0.508 0.9398)
			(end -0.508 -0.9398)
			(stroke
				(width 0)
				(type default)
			)
			(fill no)
			(layer "B.Fab")
		)
		(pad "1" smd custom
			(at 0 -0.4445)
			(size 0.1397 0.1397)
			(layers "B.Cu" "B.Mask" "B.Paste")
			(net "FM_TPM_PRSNT_N")
			(options
				(clearance outline)
				(anchor circle)
			)
			(primitives
				(gr_poly
					(pts
						(arc
							(start -0.1778 0.2794)
							(mid -0.249642 0.249642)
							(end -0.2794 0.1778)
						)
						(arc
							(start -0.2794 -0.1778)
							(mid -0.249642 -0.249642)
							(end -0.1778 -0.2794)
						)
						(arc
							(start 0.1778 -0.2794)
							(mid 0.249642 -0.249642)
							(end 0.2794 -0.1778)
						)
						(arc
							(start 0.2794 0.1778)
							(mid 0.249642 0.249642)
							(end 0.1778 0.2794)
						)
					)
					(width 0)
					(fill yes)
				)
			)
		)
		(pad "2" smd custom
			(at 0 0.4445)
			(size 0.1397 0.1397)
			(layers "B.Cu" "B.Mask" "B.Paste")
			(net "TPM_PRSNT_N_R")
			(options
				(clearance outline)
				(anchor circle)
			)
			(primitives
				(gr_poly
					(pts
						(arc
							(start -0.1778 0.2794)
							(mid -0.249642 0.249642)
							(end -0.2794 0.1778)
						)
						(arc
							(start -0.2794 -0.1778)
							(mid -0.249642 -0.249642)
							(end -0.1778 -0.2794)
						)
						(arc
							(start 0.1778 -0.2794)
							(mid 0.249642 -0.249642)
							(end 0.2794 -0.1778)
						)
						(arc
							(start 0.2794 0.1778)
							(mid 0.249642 0.249642)
							(end 0.1778 0.2794)
						)
					)
					(width 0)
					(fill yes)
				)
			)
		)
	)
	(footprint ""
		(layer "B.Cu")
		(at 95.91421 -156.82595 -90)
		(property "Reference" "R22"
			(at 0 0 90)
			(layer "B.SilkS")
			(hide yes)
			(effects
				(font
					(size 1.27 1.27)
				)
				(justify mirror)
			)
		)
		(property "Value" "4K7R2F-GP"
			(at -0.064008 -3.993896 270)
			(unlocked yes)
			(layer "B.Fab")
			(hide yes)
			(effects
				(font
					(size 1.016 1.016)
					(thickness 0.1524)
				)
				(justify mirror)
			)
		)
		(property "Device Type" "R402H16"
			(at -0.064008 -5.517896 270)
			(unlocked yes)
			(layer "B.Fab")
			(hide yes)
			(effects
				(font
					(size 1.016 1.016)
					(thickness 0.1524)
				)
				(justify mirror)
			)
		)
		(duplicate_pad_numbers_are_jumpers no)
		(fp_line
			(start -0.508 -0.9398)
			(end 0.508 -0.9398)
			(stroke
				(width 0.1524)
				(type default)
			)
			(layer "B.SilkS")
		)
		(fp_line
			(start 0.508 -0.9398)
			(end 0.508 0.9398)
			(stroke
				(width 0.1524)
				(type default)
			)
			(layer "B.SilkS")
		)
		(fp_rect
			(start 0.508 0.9398)
			(end -0.508 -0.9398)
			(stroke
				(width 0)
				(type default)
			)
			(fill no)
			(layer "B.CrtYd")
		)
		(fp_rect
			(start 0.508 0.9398)
			(end -0.508 -0.9398)
			(stroke
				(width 0)
				(type default)
			)
			(fill no)
			(layer "B.Fab")
		)
		(pad "1" smd custom
			(at 0 -0.4445 90)
			(size 0.1397 0.1397)
			(layers "B.Cu" "B.Mask" "B.Paste")
			(net "CFG_SEL1")
			(options
				(clearance outline)
				(anchor circle)
			)
			(primitives
				(gr_poly
					(pts
						(arc
							(start -0.1778 0.2794)
							(mid -0.249642 0.249642)
							(end -0.2794 0.1778)
						)
						(arc
							(start -0.2794 -0.1778)
							(mid -0.249642 -0.249642)
							(end -0.1778 -0.2794)
						)
						(arc
							(start 0.1778 -0.2794)
							(mid 0.249642 -0.249642)
							(end 0.2794 -0.1778)
						)
						(arc
							(start 0.2794 0.1778)
							(mid 0.249642 0.249642)
							(end 0.1778 0.2794)
						)
					)
					(width 0)
					(fill yes)
				)
			)
		)
		(pad "2" smd custom
			(at 0 0.4445 90)
			(size 0.1397 0.1397)
			(layers "B.Cu" "B.Mask" "B.Paste")
			(net "GND")
			(options
				(clearance outline)
				(anchor circle)
			)
			(primitives
				(gr_poly
					(pts
						(arc
							(start -0.1778 0.2794)
							(mid -0.249642 0.249642)
							(end -0.2794 0.1778)
						)
						(arc
							(start -0.2794 -0.1778)
							(mid -0.249642 -0.249642)
							(end -0.1778 -0.2794)
						)
						(arc
							(start 0.1778 -0.2794)
							(mid 0.249642 -0.249642)
							(end 0.2794 -0.1778)
						)
						(arc
							(start 0.2794 0.1778)
							(mid 0.249642 0.249642)
							(end 0.1778 0.2794)
						)
					)
					(width 0)
					(fill yes)
				)
			)
		)
	)
	(footprint ""
		(layer "B.Cu")
		(at 51.3842 -154.6352 -90)
		(property "Reference" "R366"
			(at 0 0 90)
			(layer "B.SilkS")
			(hide yes)
			(effects
				(font
					(size 1.27 1.27)
				)
				(justify mirror)
			)
		)
		(property "Value" "49K9R2F-L-GP"
			(at -0.064008 -3.993896 270)
			(unlocked yes)
			(layer "B.Fab")
			(hide yes)
			(effects
				(font
					(size 1.016 1.016)
					(thickness 0.1524)
				)
				(justify mirror)
			)
		)
		(property "Device Type" "R402H16"
			(at -0.064008 -5.517896 270)
			(unlocked yes)
			(layer "B.Fab")
			(hide yes)
			(effects
				(font
					(size 1.016 1.016)
					(thickness 0.1524)
				)
				(justify mirror)
			)
		)
		(duplicate_pad_numbers_are_jumpers no)
		(fp_line
			(start -0.508 -0.9398)
			(end 0.508 -0.9398)
			(stroke
				(width 0.1524)
				(type default)
			)
			(layer "B.SilkS")
		)
		(fp_line
			(start 0.508 -0.9398)
			(end 0.508 0.9398)
			(stroke
				(width 0.1524)
				(type default)
			)
			(layer "B.SilkS")
		)
		(fp_rect
			(start 0.508 0.9398)
			(end -0.508 -0.9398)
			(stroke
				(width 0)
				(type default)
			)
			(fill no)
			(layer "B.CrtYd")
		)
		(fp_rect
			(start 0.508 0.9398)
			(end -0.508 -0.9398)
			(stroke
				(width 0)
				(type default)
			)
			(fill no)
			(layer "B.Fab")
		)
		(pad "1" smd custom
			(at 0 -0.4445 90)
			(size 0.1397 0.1397)
			(layers "B.Cu" "B.Mask" "B.Paste")
			(net "GND")
			(options
				(clearance outline)
				(anchor circle)
			)
			(primitives
				(gr_poly
					(pts
						(arc
							(start -0.1778 0.2794)
							(mid -0.249642 0.249642)
							(end -0.2794 0.1778)
						)
						(arc
							(start -0.2794 -0.1778)
							(mid -0.249642 -0.249642)
							(end -0.1778 -0.2794)
						)
						(arc
							(start 0.1778 -0.2794)
							(mid 0.249642 -0.249642)
							(end 0.2794 -0.1778)
						)
						(arc
							(start 0.2794 0.1778)
							(mid 0.249642 0.249642)
							(end 0.1778 0.2794)
						)
					)
					(width 0)
					(fill yes)
				)
			)
		)
		(pad "2" smd custom
			(at 0 0.4445 90)
			(size 0.1397 0.1397)
			(layers "B.Cu" "B.Mask" "B.Paste")
			(net "ADCVREXT")
			(options
				(clearance outline)
				(anchor circle)
			)
			(primitives
				(gr_poly
					(pts
						(arc
							(start -0.1778 0.2794)
							(mid -0.249642 0.249642)
							(end -0.2794 0.1778)
						)
						(arc
							(start -0.2794 -0.1778)
							(mid -0.249642 -0.249642)
							(end -0.1778 -0.2794)
						)
						(arc
							(start 0.1778 -0.2794)
							(mid 0.249642 -0.249642)
							(end 0.2794 -0.1778)
						)
						(arc
							(start 0.2794 0.1778)
							(mid 0.249642 0.249642)
							(end 0.1778 0.2794)
						)
					)
					(width 0)
					(fill yes)
				)
			)
		)
	)
)
